# BARRELEYE-G2-EXPANDER-EVT-HW-EBOM-X00-20161124-add_2nd_source_X06-20161207-Final.xls — Summary (bom)
| PLATFORM SOURCING AND PSL COMPLIANCE |  |  |  |  |  |  |  |  |  |
| Platform Name: |  |  |  |  |  |  |  |  |  |
| REVISION HISTORY |  |  |  |  |  |  |  |  |  |
| BOM Revision: | ECR # | Revision Description | Originator | Date |  |  |  |  |  |
| Commodity Sourcing | # of components (X00 BOM) | % of Total | # of components (X01 BOM) | % of Total | # of components (X02 BOM) | % of Total | # of components (RTS) | % of Total | Risk Mitigation Plans in Place |
| Sole Source |  |  |  |  |  |  |  |  |  |
| Single Source |  |  |  |  |  |  |  |  |  |
| Multiple |  |  |  |  |  |  |  |  | NA |
| Total |  |  |  |  |  |  |  |  | NA |
|  |  | # of components | # of components aligned with Customer PSL* | % PSL alignment |  |  |  |  |  |
| Class 1 (Customer Managed) |  |  |  |  |  |  |  |  |  |
| Class 2 (ODM Managed to Customer PSL) |  |  |  |  |  |  |  |  |  |
| All other components(ODM Managed to ODM PSL) |  |  |  |  |  |  |  |  |  |
| *RFQ and/or Contract will list requirements for complying with Customer's PSL |  |  |  |  |  |  |  |  |  |
| Reference for quotation |  |  |  |  |  |  |  |  |  |
